(kicad_pcb
	(version 20260206)
	(generator "pcbnew")
	(generator_version "10.0")
	(general
		(thickness 1.6)
		(legacy_teardrops no)
	)
	(paper "A4")
	(title_block
		(title "pdpb — Lightning_PDPB_BRD.brd")
		(comment 1 "Lightning (Wiwynn / Facebook NVMe JBOF) / footprints 197-203 of 1140")
	)
	(layers
		(0 "F.Cu" signal "TOP")
		(4 "In1.Cu" signal "L2GND")
		(6 "In2.Cu" signal "L3")
		(8 "In3.Cu" signal "L4VCC")
		(10 "In4.Cu" signal "L5VCC")
		(12 "In5.Cu" signal "L6")
		(14 "In6.Cu" signal "L7GND")
		(2 "B.Cu" signal "BOTTOM")
		(9 "F.Adhes" user "F.Adhesive")
		(11 "B.Adhes" user "B.Adhesive")
		(13 "F.Paste" user "Package Geometry/Pastemask Top")
		(15 "B.Paste" user "Package Geometry/Pastemask Bottom")
		(5 "F.SilkS" user "Ref Des/Silkscreen Top")
		(7 "B.SilkS" user "Ref Des/Silkscreen Bottom")
		(1 "F.Mask" user "Board Geometry/Soldermask Top")
		(3 "B.Mask" user "Board Geometry/Soldermask Bottom")
		(17 "Dwgs.User" user "User.Drawings")
		(19 "Cmts.User" user "User.Comments")
		(21 "Eco1.User" user "User.Eco1")
		(23 "Eco2.User" user "User.Eco2")
		(25 "Edge.Cuts" user "Board Geometry/Outline")
		(27 "Margin" user)
		(31 "F.CrtYd" user "Package Geometry/Place Bound Top")
		(29 "B.CrtYd" user "Package Geometry/Place Bound Bottom")
		(35 "F.Fab" user "Ref Des/Assembly Top")
		(33 "B.Fab" user "Ref Des/Assembly Bottom")
	)
	(footprint ""
		(layer "F.Cu")
		(at 26.416 -94.9706 -90)
		(property "Reference" "Q71"
			(at 0 0 270)
			(layer "F.SilkS")
			(hide yes)
			(effects
				(font
					(size 1.27 1.27)
				)
			)
		)
		(property "Value" "2N7002A-7-GP"
			(at 0.127 -8.9662 270)
			(unlocked yes)
			(layer "F.Fab")
			(hide yes)
			(effects
				(font
					(size 1.016 1.016)
					(thickness 0.1524)
				)
			)
		)
		(property "Device Type" "SOT23DGS2D4H48"
			(at 0.127 -10.4902 270)
			(unlocked yes)
			(layer "F.Fab")
			(hide yes)
			(effects
				(font
					(size 1.016 1.016)
					(thickness 0.1524)
				)
			)
		)
		(duplicate_pad_numbers_are_jumpers no)
		(fp_line
			(start -1.651 1.778)
			(end 1.651 1.778)
			(stroke
				(width 0.1524)
				(type default)
			)
			(layer "F.SilkS")
		)
		(fp_line
			(start 1.651 1.778)
			(end 1.651 -1.778)
			(stroke
				(width 0.1524)
				(type default)
			)
			(layer "F.SilkS")
		)
		(fp_line
			(start -1.651 -1.778)
			(end -1.651 1.778)
			(stroke
				(width 0.1524)
				(type default)
			)
			(layer "F.SilkS")
		)
		(fp_line
			(start 1.651 -1.778)
			(end -1.651 -1.778)
			(stroke
				(width 0.1524)
				(type default)
			)
			(layer "F.SilkS")
		)
		(fp_poly
			(pts
				(xy -1.778 1.8796) (xy -1.778 -1.8796) (xy 1.778 -1.8796) (xy 1.778 1.8796)
			)
			(stroke
				(width 0)
				(type default)
			)
			(fill no)
			(layer "F.CrtYd")
		)
		(fp_poly
			(pts
				(xy -1.778 1.8796) (xy -1.778 -1.8796) (xy 1.778 -1.8796) (xy 1.778 1.8796)
			)
			(stroke
				(width 0)
				(type default)
			)
			(fill no)
			(layer "F.Fab")
		)
		(pad "D" smd custom
			(at 0 -0.9525 270)
			(size 0.1905 0.1905)
			(layers "F.Cu" "F.Mask" "F.Paste")
			(net "P12V_MOST9_GATE")
			(options
				(clearance outline)
				(anchor circle)
			)
			(primitives
				(gr_poly
					(pts
						(arc
							(start -0.1778 0.5715)
							(mid -0.321484 0.511984)
							(end -0.381 0.3683)
						)
						(arc
							(start -0.381 -0.3683)
							(mid -0.321484 -0.511984)
							(end -0.1778 -0.5715)
						)
						(arc
							(start 0.1778 -0.5715)
							(mid 0.321484 -0.511984)
							(end 0.381 -0.3683)
						)
						(arc
							(start 0.381 0.3683)
							(mid 0.321484 0.511984)
							(end 0.1778 0.5715)
						)
					)
					(width 0)
					(fill yes)
				)
			)
		)
		(pad "G" smd custom
			(at -0.98425 0.9525 270)
			(size 0.1905 0.1905)
			(layers "F.Cu" "F.Mask" "F.Paste")
			(net "SSD9_PWREN_R")
			(options
				(clearance outline)
				(anchor circle)
			)
			(primitives
				(gr_poly
					(pts
						(arc
							(start -0.1778 0.5715)
							(mid -0.321484 0.511984)
							(end -0.381 0.3683)
						)
						(arc
							(start -0.381 -0.3683)
							(mid -0.321484 -0.511984)
							(end -0.1778 -0.5715)
						)
						(arc
							(start 0.1778 -0.5715)
							(mid 0.321484 -0.511984)
							(end 0.381 -0.3683)
						)
						(arc
							(start 0.381 0.3683)
							(mid 0.321484 0.511984)
							(end 0.1778 0.5715)
						)
					)
					(width 0)
					(fill yes)
				)
			)
		)
		(pad "S" smd custom
			(at 0.98425 0.9525 270)
			(size 0.1905 0.1905)
			(layers "F.Cu" "F.Mask" "F.Paste")
			(net "GND")
			(options
				(clearance outline)
				(anchor circle)
			)
			(primitives
				(gr_poly
					(pts
						(arc
							(start -0.1778 0.5715)
							(mid -0.321484 0.511984)
							(end -0.381 0.3683)
						)
						(arc
							(start -0.381 -0.3683)
							(mid -0.321484 -0.511984)
							(end -0.1778 -0.5715)
						)
						(arc
							(start 0.1778 -0.5715)
							(mid 0.321484 -0.511984)
							(end 0.381 -0.3683)
						)
						(arc
							(start 0.381 0.3683)
							(mid 0.321484 0.511984)
							(end 0.1778 0.5715)
						)
					)
					(width 0)
					(fill yes)
				)
			)
		)
	)
	(footprint ""
		(layer "F.Cu")
		(at 26.3144 -467.3346 -90)
		(property "Reference" "R9849"
			(at 0 0 270)
			(layer "F.SilkS")
			(hide yes)
			(effects
				(font
					(size 1.27 1.27)
				)
			)
		)
		(property "Value" "0R2J-2-GP"
			(at 0.064008 -3.993896 270)
			(unlocked yes)
			(layer "F.Fab")
			(hide yes)
			(effects
				(font
					(size 1.016 1.016)
					(thickness 0.1524)
				)
			)
		)
		(property "Device Type" "R402H16"
			(at 0.064008 -5.517896 270)
			(unlocked yes)
			(layer "F.Fab")
			(hide yes)
			(effects
				(font
					(size 1.016 1.016)
					(thickness 0.1524)
				)
			)
		)
		(duplicate_pad_numbers_are_jumpers no)
		(fp_line
			(start -0.508 -0.9398)
			(end -0.508 0.9398)
			(stroke
				(width 0.1524)
				(type default)
			)
			(layer "F.SilkS")
		)
		(fp_line
			(start 0.508 -0.9398)
			(end -0.508 -0.9398)
			(stroke
				(width 0.1524)
				(type default)
			)
			(layer "F.SilkS")
		)
		(fp_rect
			(start -0.508 0.9398)
			(end 0.508 -0.9398)
			(stroke
				(width 0)
				(type default)
			)
			(fill no)
			(layer "F.CrtYd")
		)
		(fp_rect
			(start -0.508 0.9398)
			(end 0.508 -0.9398)
			(stroke
				(width 0)
				(type default)
			)
			(fill no)
			(layer "F.Fab")
		)
		(pad "1" smd custom
			(at 0 -0.4445 270)
			(size 0.1397 0.1397)
			(layers "F.Cu" "F.Mask" "F.Paste")
			(net "SSD_ACT_DR10_R")
			(options
				(clearance outline)
				(anchor circle)
			)
			(primitives
				(gr_poly
					(pts
						(arc
							(start -0.1778 -0.2794)
							(mid -0.249642 -0.249642)
							(end -0.2794 -0.1778)
						)
						(arc
							(start -0.2794 0.1778)
							(mid -0.249642 0.249642)
							(end -0.1778 0.2794)
						)
						(arc
							(start 0.1778 0.2794)
							(mid 0.249642 0.249642)
							(end 0.2794 0.1778)
						)
						(arc
							(start 0.2794 -0.1778)
							(mid 0.249642 -0.249642)
							(end 0.1778 -0.2794)
						)
					)
					(width 0)
					(fill yes)
				)
			)
		)
		(pad "2" smd custom
			(at 0 0.4445 270)
			(size 0.1397 0.1397)
			(layers "F.Cu" "F.Mask" "F.Paste")
			(net "SSD_ACT_DR10")
			(options
				(clearance outline)
				(anchor circle)
			)
			(primitives
				(gr_poly
					(pts
						(arc
							(start -0.1778 -0.2794)
							(mid -0.249642 -0.249642)
							(end -0.2794 -0.1778)
						)
						(arc
							(start -0.2794 0.1778)
							(mid -0.249642 0.249642)
							(end -0.1778 0.2794)
						)
						(arc
							(start 0.1778 0.2794)
							(mid 0.249642 0.249642)
							(end 0.2794 0.1778)
						)
						(arc
							(start 0.2794 -0.1778)
							(mid 0.249642 -0.249642)
							(end 0.1778 -0.2794)
						)
					)
					(width 0)
					(fill yes)
				)
			)
		)
	)
	(footprint ""
		(layer "F.Cu")
		(at 47.879 -351.028 -90)
		(property "Reference" "R9470"
			(at 0 0 270)
			(layer "F.SilkS")
			(hide yes)
			(effects
				(font
					(size 1.27 1.27)
				)
			)
		)
		(property "Value" "330R2F-GP"
			(at 0.064008 -3.993896 270)
			(unlocked yes)
			(layer "F.Fab")
			(hide yes)
			(effects
				(font
					(size 1.016 1.016)
					(thickness 0.1524)
				)
			)
		)
		(property "Device Type" "R402H16"
			(at 0.064008 -5.517896 270)
			(unlocked yes)
			(layer "F.Fab")
			(hide yes)
			(effects
				(font
					(size 1.016 1.016)
					(thickness 0.1524)
				)
			)
		)
		(duplicate_pad_numbers_are_jumpers no)
		(fp_line
			(start -0.508 -0.9398)
			(end -0.508 0.9398)
			(stroke
				(width 0.1524)
				(type default)
			)
			(layer "F.SilkS")
		)
		(fp_line
			(start 0.508 -0.9398)
			(end -0.508 -0.9398)
			(stroke
				(width 0.1524)
				(type default)
			)
			(layer "F.SilkS")
		)
		(fp_rect
			(start -0.508 0.9398)
			(end 0.508 -0.9398)
			(stroke
				(width 0)
				(type default)
			)
			(fill no)
			(layer "F.CrtYd")
		)
		(fp_rect
			(start -0.508 0.9398)
			(end 0.508 -0.9398)
			(stroke
				(width 0)
				(type default)
			)
			(fill no)
			(layer "F.Fab")
		)
		(pad "1" smd custom
			(at 0 -0.4445 270)
			(size 0.1397 0.1397)
			(layers "F.Cu" "F.Mask" "F.Paste")
			(net "P3V3")
			(options
				(clearance outline)
				(anchor circle)
			)
			(primitives
				(gr_poly
					(pts
						(arc
							(start -0.1778 -0.2794)
							(mid -0.249642 -0.249642)
							(end -0.2794 -0.1778)
						)
						(arc
							(start -0.2794 0.1778)
							(mid -0.249642 0.249642)
							(end -0.1778 0.2794)
						)
						(arc
							(start 0.1778 0.2794)
							(mid 0.249642 0.249642)
							(end 0.2794 0.1778)
						)
						(arc
							(start 0.2794 -0.1778)
							(mid 0.249642 -0.249642)
							(end 0.1778 -0.2794)
						)
					)
					(width 0)
					(fill yes)
				)
			)
		)
		(pad "2" smd custom
			(at 0 0.4445 270)
			(size 0.1397 0.1397)
			(layers "F.Cu" "F.Mask" "F.Paste")
			(net "DRV_ATTN_6")
			(options
				(clearance outline)
				(anchor circle)
			)
			(primitives
				(gr_poly
					(pts
						(arc
							(start -0.1778 -0.2794)
							(mid -0.249642 -0.249642)
							(end -0.2794 -0.1778)
						)
						(arc
							(start -0.2794 0.1778)
							(mid -0.249642 0.249642)
							(end -0.1778 0.2794)
						)
						(arc
							(start 0.1778 0.2794)
							(mid 0.249642 0.249642)
							(end 0.2794 0.1778)
						)
						(arc
							(start 0.2794 -0.1778)
							(mid 0.249642 -0.249642)
							(end 0.1778 -0.2794)
						)
					)
					(width 0)
					(fill yes)
				)
			)
		)
	)
	(footprint ""
		(layer "F.Cu")
		(at 70.739 -360.553 90)
		(property "Reference" "SR978"
			(at 0 0 90)
			(layer "F.SilkS")
			(hide yes)
			(effects
				(font
					(size 1.27 1.27)
				)
			)
		)
		(property "Value" "2KR2F-3-GP"
			(at 0.064008 -3.993896 90)
			(unlocked yes)
			(layer "F.Fab")
			(hide yes)
			(effects
				(font
					(size 1.016 1.016)
					(thickness 0.1524)
				)
			)
		)
		(property "Device Type" "R402H16"
			(at 0.064008 -5.517896 90)
			(unlocked yes)
			(layer "F.Fab")
			(hide yes)
			(effects
				(font
					(size 1.016 1.016)
					(thickness 0.1524)
				)
			)
		)
		(duplicate_pad_numbers_are_jumpers no)
		(fp_line
			(start 0.508 -0.9398)
			(end -0.508 -0.9398)
			(stroke
				(width 0.1524)
				(type default)
			)
			(layer "F.SilkS")
		)
		(fp_line
			(start -0.508 -0.9398)
			(end -0.508 0.9398)
			(stroke
				(width 0.1524)
				(type default)
			)
			(layer "F.SilkS")
		)
		(fp_rect
			(start -0.508 0.9398)
			(end 0.508 -0.9398)
			(stroke
				(width 0)
				(type default)
			)
			(fill no)
			(layer "F.CrtYd")
		)
		(fp_rect
			(start -0.508 0.9398)
			(end 0.508 -0.9398)
			(stroke
				(width 0)
				(type default)
			)
			(fill no)
			(layer "F.Fab")
		)
		(pad "1" smd custom
			(at 0 -0.4445 90)
			(size 0.1397 0.1397)
			(layers "F.Cu" "F.Mask" "F.Paste")
			(net "P3V3")
			(options
				(clearance outline)
				(anchor circle)
			)
			(primitives
				(gr_poly
					(pts
						(arc
							(start -0.1778 -0.2794)
							(mid -0.249642 -0.249642)
							(end -0.2794 -0.1778)
						)
						(arc
							(start -0.2794 0.1778)
							(mid -0.249642 0.249642)
							(end -0.1778 0.2794)
						)
						(arc
							(start 0.1778 0.2794)
							(mid 0.249642 0.249642)
							(end 0.2794 0.1778)
						)
						(arc
							(start 0.2794 -0.1778)
							(mid 0.249642 -0.249642)
							(end 0.1778 -0.2794)
						)
					)
					(width 0)
					(fill yes)
				)
			)
		)
		(pad "2" smd custom
			(at 0 0.4445 90)
			(size 0.1397 0.1397)
			(layers "F.Cu" "F.Mask" "F.Paste")
			(net "SDA_DR7")
			(options
				(clearance outline)
				(anchor circle)
			)
			(primitives
				(gr_poly
					(pts
						(arc
							(start -0.1778 -0.2794)
							(mid -0.249642 -0.249642)
							(end -0.2794 -0.1778)
						)
						(arc
							(start -0.2794 0.1778)
							(mid -0.249642 0.249642)
							(end -0.1778 0.2794)
						)
						(arc
							(start 0.1778 0.2794)
							(mid 0.249642 0.249642)
							(end 0.2794 0.1778)
						)
						(arc
							(start 0.2794 -0.1778)
							(mid 0.249642 -0.249642)
							(end 0.1778 -0.2794)
						)
					)
					(width 0)
					(fill yes)
				)
			)
		)
	)
	(footprint ""
		(layer "F.Cu")
		(at 91.313 -92.964)
		(property "Reference" "R9123"
			(at 0 0 0)
			(layer "F.SilkS")
			(hide yes)
			(effects
				(font
					(size 1.27 1.27)
				)
			)
		)
		(property "Value" "27R2F-GP"
			(at 0.064008 -3.993896 0)
			(unlocked yes)
			(layer "F.Fab")
			(hide yes)
			(effects
				(font
					(size 1.016 1.016)
					(thickness 0.1524)
				)
			)
		)
		(property "Device Type" "R402H16"
			(at 0.064008 -5.517896 0)
			(unlocked yes)
			(layer "F.Fab")
			(hide yes)
			(effects
				(font
					(size 1.016 1.016)
					(thickness 0.1524)
				)
			)
		)
		(duplicate_pad_numbers_are_jumpers no)
		(fp_line
			(start -0.508 -0.9398)
			(end -0.508 0.9398)
			(stroke
				(width 0.1524)
				(type default)
			)
			(layer "F.SilkS")
		)
		(fp_line
			(start 0.508 -0.9398)
			(end -0.508 -0.9398)
			(stroke
				(width 0.1524)
				(type default)
			)
			(layer "F.SilkS")
		)
		(fp_rect
			(start -0.508 0.9398)
			(end 0.508 -0.9398)
			(stroke
				(width 0)
				(type default)
			)
			(fill no)
			(layer "F.CrtYd")
		)
		(fp_rect
			(start -0.508 0.9398)
			(end 0.508 -0.9398)
			(stroke
				(width 0)
				(type default)
			)
			(fill no)
			(layer "F.Fab")
		)
		(pad "1" smd custom
			(at 0 -0.4445)
			(size 0.1397 0.1397)
			(layers "F.Cu" "F.Mask" "F.Paste")
			(net "PE_CLK_100M_DR9_1_R_N")
			(options
				(clearance outline)
				(anchor circle)
			)
			(primitives
				(gr_poly
					(pts
						(arc
							(start -0.1778 -0.2794)
							(mid -0.249642 -0.249642)
							(end -0.2794 -0.1778)
						)
						(arc
							(start -0.2794 0.1778)
							(mid -0.249642 0.249642)
							(end -0.1778 0.2794)
						)
						(arc
							(start 0.1778 0.2794)
							(mid 0.249642 0.249642)
							(end 0.2794 0.1778)
						)
						(arc
							(start 0.2794 -0.1778)
							(mid 0.249642 -0.249642)
							(end 0.1778 -0.2794)
						)
					)
					(width 0)
					(fill yes)
				)
			)
		)
		(pad "2" smd custom
			(at 0 0.4445)
			(size 0.1397 0.1397)
			(layers "F.Cu" "F.Mask" "F.Paste")
			(net "PE_CLK100M_DR9_1_N")
			(options
				(clearance outline)
				(anchor circle)
			)
			(primitives
				(gr_poly
					(pts
						(arc
							(start -0.1778 -0.2794)
							(mid -0.249642 -0.249642)
							(end -0.2794 -0.1778)
						)
						(arc
							(start -0.2794 0.1778)
							(mid -0.249642 0.249642)
							(end -0.1778 0.2794)
						)
						(arc
							(start 0.1778 0.2794)
							(mid 0.249642 0.249642)
							(end 0.2794 0.1778)
						)
						(arc
							(start 0.2794 -0.1778)
							(mid 0.249642 -0.249642)
							(end 0.1778 -0.2794)
						)
					)
					(width 0)
					(fill yes)
				)
			)
		)
	)
	(footprint ""
		(layer "F.Cu")
		(at 88.011 -309.88)
		(property "Reference" "C8910"
			(at 0 0 0)
			(layer "F.SilkS")
			(hide yes)
			(effects
				(font
					(size 1.27 1.27)
				)
			)
		)
		(property "Value" "SCD1U16V2KX-3GP"
			(at 1.1811 -2.7051 0)
			(unlocked yes)
			(layer "F.Fab")
			(hide yes)
			(effects
				(font
					(size 1.016 1.016)
					(thickness 0.1524)
				)
			)
		)
		(property "Device Type" "C402H22"
			(at 1.1811 -4.2291 0)
			(unlocked yes)
			(layer "F.Fab")
			(hide yes)
			(effects
				(font
					(size 1.016 1.016)
					(thickness 0.1524)
				)
			)
		)
		(duplicate_pad_numbers_are_jumpers no)
		(fp_rect
			(start -0.4318 0.9525)
			(end 0.4318 -0.9525)
			(stroke
				(width 0)
				(type default)
			)
			(fill no)
			(layer "F.CrtYd")
		)
		(fp_rect
			(start -0.4318 0.9525)
			(end 0.4318 -0.9525)
			(stroke
				(width 0)
				(type default)
			)
			(fill no)
			(layer "F.Fab")
		)
		(pad "1" smd custom
			(at 0 -0.4445)
			(size 0.1524 0.1524)
			(layers "F.Cu" "F.Mask" "F.Paste")
			(net "VDDA_2")
			(options
				(clearance outline)
				(anchor circle)
			)
			(primitives
				(gr_poly
					(pts
						(arc
							(start 0.3048 -0.2032)
							(mid 0.275042 -0.275042)
							(end 0.2032 -0.3048)
						)
						(arc
							(start -0.2032 -0.3048)
							(mid -0.275042 -0.275042)
							(end -0.3048 -0.2032)
						)
						(arc
							(start -0.3048 0.2032)
							(mid -0.275042 0.275042)
							(end -0.2032 0.3048)
						)
						(arc
							(start 0.2032 0.3048)
							(mid 0.275042 0.275042)
							(end 0.3048 0.2032)
						)
					)
					(width 0)
					(fill yes)
				)
			)
		)
		(pad "2" smd custom
			(at 0 0.4445)
			(size 0.1524 0.1524)
			(layers "F.Cu" "F.Mask" "F.Paste")
			(net "GND")
			(options
				(clearance outline)
				(anchor circle)
			)
			(primitives
				(gr_poly
					(pts
						(arc
							(start 0.3048 -0.2032)
							(mid 0.275042 -0.275042)
							(end 0.2032 -0.3048)
						)
						(arc
							(start -0.2032 -0.3048)
							(mid -0.275042 -0.275042)
							(end -0.3048 -0.2032)
						)
						(arc
							(start -0.3048 0.2032)
							(mid -0.275042 0.275042)
							(end -0.2032 0.3048)
						)
						(arc
							(start 0.2032 0.3048)
							(mid 0.275042 0.275042)
							(end 0.3048 0.2032)
						)
					)
					(width 0)
					(fill yes)
				)
			)
		)
	)
	(footprint ""
		(layer "F.Cu")
		(at 38.8366 -109.8804 180)
		(property "Reference" "R564"
			(at 0 0 180)
			(layer "F.SilkS")
			(hide yes)
			(effects
				(font
					(size 1.27 1.27)
				)
			)
		)
		(property "Value" "200KR2F-L-GP"
			(at 0.064008 -3.993896 180)
			(unlocked yes)
			(layer "F.Fab")
			(hide yes)
			(effects
				(font
					(size 1.016 1.016)
					(thickness 0.1524)
				)
			)
		)
		(property "Device Type" "R402H16"
			(at 0.064008 -5.517896 180)
			(unlocked yes)
			(layer "F.Fab")
			(hide yes)
			(effects
				(font
					(size 1.016 1.016)
					(thickness 0.1524)
				)
			)
		)
		(duplicate_pad_numbers_are_jumpers no)
		(fp_line
			(start 0.508 -0.9398)
			(end -0.508 -0.9398)
			(stroke
				(width 0.1524)
				(type default)
			)
			(layer "F.SilkS")
		)
		(fp_line
			(start -0.508 -0.9398)
			(end -0.508 0.9398)
			(stroke
				(width 0.1524)
				(type default)
			)
			(layer "F.SilkS")
		)
		(fp_rect
			(start -0.508 0.9398)
			(end 0.508 -0.9398)
			(stroke
				(width 0)
				(type default)
			)
			(fill no)
			(layer "F.CrtYd")
		)
		(fp_rect
			(start -0.508 0.9398)
			(end 0.508 -0.9398)
			(stroke
				(width 0)
				(type default)
			)
			(fill no)
			(layer "F.Fab")
		)
		(pad "1" smd custom
			(at 0 -0.4445 180)
			(size 0.1397 0.1397)
			(layers "F.Cu" "F.Mask" "F.Paste")
			(net "SW_SSD13_R")
			(options
				(clearance outline)
				(anchor circle)
			)
			(primitives
				(gr_poly
					(pts
						(arc
							(start -0.1778 -0.2794)
							(mid -0.249642 -0.249642)
							(end -0.2794 -0.1778)
						)
						(arc
							(start -0.2794 0.1778)
							(mid -0.249642 0.249642)
							(end -0.1778 0.2794)
						)
						(arc
							(start 0.1778 0.2794)
							(mid 0.249642 0.249642)
							(end 0.2794 0.1778)
						)
						(arc
							(start 0.2794 -0.1778)
							(mid 0.249642 -0.249642)
							(end 0.1778 -0.2794)
						)
					)
					(width 0)
					(fill yes)
				)
			)
		)
		(pad "2" smd custom
			(at 0 0.4445 180)
			(size 0.1397 0.1397)
			(layers "F.Cu" "F.Mask" "F.Paste")
			(net "SW_SSD13_N")
			(options
				(clearance outline)
				(anchor circle)
			)
			(primitives
				(gr_poly
					(pts
						(arc
							(start -0.1778 -0.2794)
							(mid -0.249642 -0.249642)
							(end -0.2794 -0.1778)
						)
						(arc
							(start -0.2794 0.1778)
							(mid -0.249642 0.249642)
							(end -0.1778 0.2794)
						)
						(arc
							(start 0.1778 0.2794)
							(mid 0.249642 0.249642)
							(end 0.2794 0.1778)
						)
						(arc
							(start 0.2794 -0.1778)
							(mid 0.249642 -0.249642)
							(end 0.1778 -0.2794)
						)
					)
					(width 0)
					(fill yes)
				)
			)
		)
	)
)
